(kicad_pcb
	(version 20260206)
	(generator "pcbnew")
	(generator_version "10.0")
	(general
		(thickness 1.6)
		(legacy_teardrops no)
	)
	(paper "A4")
	(title_block
		(title "netronome-mezz — pcbd0082-001_rev01_jul9_a.brd")
		(comment 1 "Open CloudServer (Microsoft) / footprints 206-209 of 714")
	)
	(layers
		(0 "F.Cu" signal "TOP")
		(4 "In1.Cu" signal "02_GND")
		(6 "In2.Cu" signal "03_SIG")
		(8 "In3.Cu" signal "04_SIG")
		(10 "In4.Cu" signal "05_GND")
		(12 "In5.Cu" signal "06_PWR1")
		(14 "In6.Cu" signal "07_SIG")
		(16 "In7.Cu" signal "08_SIG")
		(18 "In8.Cu" signal "09_GND")
		(2 "B.Cu" signal "BOTTOM")
		(9 "F.Adhes" user "F.Adhesive")
		(11 "B.Adhes" user "B.Adhesive")
		(13 "F.Paste" user "Package Geometry/Pastemask Top")
		(15 "B.Paste" user "Package Geometry/Pastemask Bottom")
		(5 "F.SilkS" user "Ref Des/Silkscreen Top")
		(7 "B.SilkS" user "Ref Des/Silkscreen Bottom")
		(1 "F.Mask" user "Board Geometry/Soldermask Top")
		(3 "B.Mask" user "Board Geometry/Soldermask Bottom")
		(17 "Dwgs.User" user "User.Drawings")
		(19 "Cmts.User" user "User.Comments")
		(21 "Eco1.User" user "User.Eco1")
		(23 "Eco2.User" user "User.Eco2")
		(25 "Edge.Cuts" user "Board Geometry/Outline")
		(27 "Margin" user)
		(31 "F.CrtYd" user "Package Geometry/Place Bound Top")
		(29 "B.CrtYd" user "Package Geometry/Place Bound Bottom")
		(35 "F.Fab" user "Ref Des/Assembly Top")
		(33 "B.Fab" user "Ref Des/Assembly Bottom")
		(45 "User.4" user "COMPVAL_TYPE_BOTTOM")
	)
	(footprint ""
		(layer "F.Cu")
		(at 22.352 3.937)
		(property "Reference" "U20"
			(at 2.921 1.42367 0)
			(unlocked yes)
			(layer "F.SilkS")
			(effects
				(font
					(size 0.7874 0.5842)
					(thickness 0.127)
				)
				(justify left)
			)
		)
		(property "Value" "*"
			(at -0.4826 -0.148107 0)
			(unlocked yes)
			(layer "F.Fab")
			(hide yes)
			(effects
				(font
					(size 1.27 0.9652)
					(thickness 0.000001)
				)
				(justify left)
			)
		)
		(property "Device Type" "ICSO0128"
			(at -0.4826 -0.148107 0)
			(unlocked yes)
			(layer "F.Fab")
			(hide yes)
			(effects
				(font
					(size 1.27 0.9652)
					(thickness 0.000001)
				)
				(justify left)
			)
		)
		(duplicate_pad_numbers_are_jumpers no)
		(fp_line
			(start -2.159 -1.651)
			(end -2.159 -0.762)
			(stroke
				(width 0.1524)
				(type default)
			)
			(layer "F.SilkS")
		)
		(fp_line
			(start -2.159 -1.651)
			(end -2.159 -0.762)
			(stroke
				(width 0.1524)
				(type default)
			)
			(layer "F.SilkS")
		)
		(fp_line
			(start -2.159 1.651)
			(end -2.159 0.762)
			(stroke
				(width 0.1524)
				(type default)
			)
			(layer "F.SilkS")
		)
		(fp_line
			(start -1.778 -1.651)
			(end -2.159 -1.651)
			(stroke
				(width 0.1524)
				(type default)
			)
			(layer "F.SilkS")
		)
		(fp_line
			(start -1.778 1.651)
			(end -2.159 1.143)
			(stroke
				(width 0.1524)
				(type default)
			)
			(layer "F.SilkS")
		)
		(fp_line
			(start -1.778 1.651)
			(end -2.159 1.651)
			(stroke
				(width 0.1524)
				(type default)
			)
			(layer "F.SilkS")
		)
		(fp_line
			(start 1.778 -1.651)
			(end 2.159 -1.651)
			(stroke
				(width 0.1524)
				(type default)
			)
			(layer "F.SilkS")
		)
		(fp_line
			(start 1.778 1.651)
			(end 2.159 1.651)
			(stroke
				(width 0.1524)
				(type default)
			)
			(layer "F.SilkS")
		)
		(fp_line
			(start 2.159 -1.651)
			(end 2.159 -0.762)
			(stroke
				(width 0.1524)
				(type default)
			)
			(layer "F.SilkS")
		)
		(fp_line
			(start 2.159 -1.651)
			(end 2.159 -0.762)
			(stroke
				(width 0.1524)
				(type default)
			)
			(layer "F.SilkS")
		)
		(fp_line
			(start 2.159 1.651)
			(end 2.159 0.762)
			(stroke
				(width 0.1524)
				(type default)
			)
			(layer "F.SilkS")
		)
		(fp_arc
			(start -2.0828 1.910131)
			(mid -2.057529 1.906285)
			(end -2.032 1.905)
			(stroke
				(width 0.1524)
				(type default)
			)
			(layer "F.SilkS")
		)
		(fp_arc
			(start -2.032 1.905)
			(mid -1.927492 1.927496)
			(end -1.8415 1.991004)
			(stroke
				(width 0.1524)
				(type default)
			)
			(layer "F.SilkS")
		)
		(fp_arc
			(start -2.032 2.413)
			(mid -2.05753 2.411703)
			(end -2.0828 2.407844)
			(stroke
				(width 0.1524)
				(type default)
			)
			(layer "F.SilkS")
		)
		(fp_arc
			(start -1.8415 2.327148)
			(mid -1.927511 2.390579)
			(end -2.032 2.413)
			(stroke
				(width 0.1524)
				(type default)
			)
			(layer "F.SilkS")
		)
		(fp_circle
			(center -2.032 2.159)
			(end -1.778 2.159)
			(stroke
				(width 0.1524)
				(type default)
			)
			(fill no)
			(layer "F.SilkS")
		)
		(fp_poly
			(pts
				(xy -2.667 2.159) (xy 2.667 2.159) (xy 2.667 -2.159) (xy -2.667 -2.159)
			)
			(stroke
				(width 0)
				(type default)
			)
			(fill no)
			(layer "F.CrtYd")
		)
		(fp_line
			(start -1.8034 -1.2954)
			(end -1.8034 1.2954)
			(stroke
				(width 0.1524)
				(type default)
			)
			(layer "F.Fab")
		)
		(fp_line
			(start -1.8034 1.2954)
			(end 1.8034 1.2954)
			(stroke
				(width 0.1524)
				(type default)
			)
			(layer "F.Fab")
		)
		(fp_line
			(start 1.8034 -1.2954)
			(end -1.8034 -1.2954)
			(stroke
				(width 0.1524)
				(type default)
			)
			(layer "F.Fab")
		)
		(fp_line
			(start 1.8034 1.2954)
			(end 1.8034 -1.2954)
			(stroke
				(width 0.1524)
				(type default)
			)
			(layer "F.Fab")
		)
		(fp_circle
			(center -1.27 0.762)
			(end -0.986003 0.762)
			(stroke
				(width 0.1524)
				(type default)
			)
			(fill no)
			(layer "F.Fab")
		)
		(fp_text user "1"
			(at -4.318 0.66167 0)
			(unlocked yes)
			(layer "F.SilkS")
			(effects
				(font
					(size 0.7874 0.5842)
					(thickness 0.127)
				)
				(justify left)
			)
		)
		(fp_text user "16"
			(at -3.65633 0 90)
			(unlocked yes)
			(layer "F.SilkS")
			(effects
				(font
					(size 0.7874 0.5842)
					(thickness 0.127)
				)
				(justify left)
			)
		)
		(fp_text user "15"
			(at -1.87833 -1.778 90)
			(unlocked yes)
			(layer "F.SilkS")
			(effects
				(font
					(size 0.7874 0.5842)
					(thickness 0.127)
				)
				(justify left)
			)
		)
		(fp_text user "2"
			(at -1.24333 3.429 90)
			(unlocked yes)
			(layer "F.SilkS")
			(effects
				(font
					(size 0.7874 0.5842)
					(thickness 0.127)
				)
				(justify left)
			)
		)
		(fp_text user "7"
			(at 1.29667 3.302 90)
			(unlocked yes)
			(layer "F.SilkS")
			(effects
				(font
					(size 0.7874 0.5842)
					(thickness 0.127)
				)
				(justify left)
			)
		)
		(fp_text user "10"
			(at 2.159 -1.87833 0)
			(unlocked yes)
			(layer "F.SilkS")
			(effects
				(font
					(size 0.7874 0.5842)
					(thickness 0.127)
				)
				(justify left)
			)
		)
		(fp_text user "9"
			(at 2.3749 -0.472872 0)
			(unlocked yes)
			(layer "F.SilkS")
			(effects
				(font
					(size 0.7874 0.5842)
					(thickness 0.127)
				)
				(justify left)
			)
		)
		(fp_text user "8"
			(at 2.3749 0.670154 0)
			(unlocked yes)
			(layer "F.SilkS")
			(effects
				(font
					(size 0.7874 0.5842)
					(thickness 0.127)
				)
				(justify left)
			)
		)
		(pad "1" smd custom
			(at -1.7018 0.250012 270)
			(size 0.06985 0.06985)
			(layers "F.Cu" "F.Mask" "F.Paste")
			(net "13N4321")
			(options
				(clearance outline)
				(anchor circle)
			)
			(primitives
				(gr_poly
					(pts
						(xy 0.1397 0.4064)
						(arc
							(start 0.1397 -0.2667)
							(mid 0 -0.4064)
							(end -0.1397 -0.2667)
						)
						(xy -0.1397 0.4064)
					)
					(width 0)
					(fill yes)
				)
			)
		)
		(pad "2" smd custom
			(at -1.25001 1.1938)
			(size 0.06985 0.06985)
			(layers "F.Cu" "F.Mask" "F.Paste")
			(net "_NC_U20_74CBTLV_1B1")
			(options
				(clearance outline)
				(anchor circle)
			)
			(primitives
				(gr_poly
					(pts
						(xy 0.1397 0.4064)
						(arc
							(start 0.1397 -0.2667)
							(mid 0 -0.4064)
							(end -0.1397 -0.2667)
						)
						(xy -0.1397 0.4064)
					)
					(width 0)
					(fill yes)
				)
			)
		)
		(pad "3" smd custom
			(at -0.750011 1.1938)
			(size 0.06985 0.06985)
			(layers "F.Cu" "F.Mask" "F.Paste")
			(net "MUX_NFP_SMBUS_ALERT_L")
			(options
				(clearance outline)
				(anchor circle)
			)
			(primitives
				(gr_poly
					(pts
						(xy 0.1397 0.4064)
						(arc
							(start 0.1397 -0.2667)
							(mid 0 -0.4064)
							(end -0.1397 -0.2667)
						)
						(xy -0.1397 0.4064)
					)
					(width 0)
					(fill yes)
				)
			)
		)
		(pad "4" smd custom
			(at -0.250012 1.1938)
			(size 0.06985 0.06985)
			(layers "F.Cu" "F.Mask" "F.Paste")
			(net "NFP_SMBUS_ALERT_L")
			(options
				(clearance outline)
				(anchor circle)
			)
			(primitives
				(gr_poly
					(pts
						(xy 0.1397 0.4064)
						(arc
							(start 0.1397 -0.2667)
							(mid 0 -0.4064)
							(end -0.1397 -0.2667)
						)
						(xy -0.1397 0.4064)
					)
					(width 0)
					(fill yes)
				)
			)
		)
		(pad "5" smd custom
			(at 0.250012 1.1938)
			(size 0.06985 0.06985)
			(layers "F.Cu" "F.Mask" "F.Paste")
			(net "_NC_U20_74CBTLV_2B1")
			(options
				(clearance outline)
				(anchor circle)
			)
			(primitives
				(gr_poly
					(pts
						(xy 0.1397 0.4064)
						(arc
							(start 0.1397 -0.2667)
							(mid 0 -0.4064)
							(end -0.1397 -0.2667)
						)
						(xy -0.1397 0.4064)
					)
					(width 0)
					(fill yes)
				)
			)
		)
		(pad "6" smd custom
			(at 0.750011 1.1938)
			(size 0.06985 0.06985)
			(layers "F.Cu" "F.Mask" "F.Paste")
			(net "MUX_NFP_SMBUS_SDA")
			(options
				(clearance outline)
				(anchor circle)
			)
			(primitives
				(gr_poly
					(pts
						(xy 0.1397 0.4064)
						(arc
							(start 0.1397 -0.2667)
							(mid 0 -0.4064)
							(end -0.1397 -0.2667)
						)
						(xy -0.1397 0.4064)
					)
					(width 0)
					(fill yes)
				)
			)
		)
		(pad "7" smd custom
			(at 1.25001 1.1938)
			(size 0.06985 0.06985)
			(layers "F.Cu" "F.Mask" "F.Paste")
			(net "NFP_SMBUS_SDA")
			(options
				(clearance outline)
				(anchor circle)
			)
			(primitives
				(gr_poly
					(pts
						(xy 0.1397 0.4064)
						(arc
							(start 0.1397 -0.2667)
							(mid 0 -0.4064)
							(end -0.1397 -0.2667)
						)
						(xy -0.1397 0.4064)
					)
					(width 0)
					(fill yes)
				)
			)
		)
		(pad "8" smd custom
			(at 1.7018 0.250012 90)
			(size 0.06985 0.06985)
			(layers "F.Cu" "F.Mask" "F.Paste")
			(net "GND")
			(options
				(clearance outline)
				(anchor circle)
			)
			(primitives
				(gr_poly
					(pts
						(xy 0.1397 0.4064)
						(arc
							(start 0.1397 -0.2667)
							(mid 0 -0.4064)
							(end -0.1397 -0.2667)
						)
						(xy -0.1397 0.4064)
					)
					(width 0)
					(fill yes)
				)
			)
		)
		(pad "9" smd custom
			(at 1.7018 -0.250012 90)
			(size 0.06985 0.06985)
			(layers "F.Cu" "F.Mask" "F.Paste")
			(net "NFP_SMBUS_SCL")
			(options
				(clearance outline)
				(anchor circle)
			)
			(primitives
				(gr_poly
					(pts
						(xy 0.1397 0.4064)
						(arc
							(start 0.1397 -0.2667)
							(mid 0 -0.4064)
							(end -0.1397 -0.2667)
						)
						(xy -0.1397 0.4064)
					)
					(width 0)
					(fill yes)
				)
			)
		)
		(pad "10" smd custom
			(at 1.25001 -1.1938 180)
			(size 0.06985 0.06985)
			(layers "F.Cu" "F.Mask" "F.Paste")
			(net "MUX_NFP_SMBUS_SCL")
			(options
				(clearance outline)
				(anchor circle)
			)
			(primitives
				(gr_poly
					(pts
						(xy 0.1397 0.4064)
						(arc
							(start 0.1397 -0.2667)
							(mid 0 -0.4064)
							(end -0.1397 -0.2667)
						)
						(xy -0.1397 0.4064)
					)
					(width 0)
					(fill yes)
				)
			)
		)
		(pad "11" smd custom
			(at 0.750011 -1.1938 180)
			(size 0.06985 0.06985)
			(layers "F.Cu" "F.Mask" "F.Paste")
			(net "_NC_U20_74CBTLV_3B1")
			(options
				(clearance outline)
				(anchor circle)
			)
			(primitives
				(gr_poly
					(pts
						(xy 0.1397 0.4064)
						(arc
							(start 0.1397 -0.2667)
							(mid 0 -0.4064)
							(end -0.1397 -0.2667)
						)
						(xy -0.1397 0.4064)
					)
					(width 0)
					(fill yes)
				)
			)
		)
		(pad "12" smd custom
			(at 0.250012 -1.1938 180)
			(size 0.06985 0.06985)
			(layers "F.Cu" "F.Mask" "F.Paste")
			(net "NFP_PCIE0_WAKE_L")
			(options
				(clearance outline)
				(anchor circle)
			)
			(primitives
				(gr_poly
					(pts
						(xy 0.1397 0.4064)
						(arc
							(start 0.1397 -0.2667)
							(mid 0 -0.4064)
							(end -0.1397 -0.2667)
						)
						(xy -0.1397 0.4064)
					)
					(width 0)
					(fill yes)
				)
			)
		)
		(pad "13" smd custom
			(at -0.250012 -1.1938 180)
			(size 0.06985 0.06985)
			(layers "F.Cu" "F.Mask" "F.Paste")
			(net "MUX_NFP_PCIE0_WAKE_L")
			(options
				(clearance outline)
				(anchor circle)
			)
			(primitives
				(gr_poly
					(pts
						(xy 0.1397 0.4064)
						(arc
							(start 0.1397 -0.2667)
							(mid 0 -0.4064)
							(end -0.1397 -0.2667)
						)
						(xy -0.1397 0.4064)
					)
					(width 0)
					(fill yes)
				)
			)
		)
		(pad "14" smd custom
			(at -0.750011 -1.1938 180)
			(size 0.06985 0.06985)
			(layers "F.Cu" "F.Mask" "F.Paste")
			(net "_NC_U20_74CBTLV_4B1")
			(options
				(clearance outline)
				(anchor circle)
			)
			(primitives
				(gr_poly
					(pts
						(xy 0.1397 0.4064)
						(arc
							(start 0.1397 -0.2667)
							(mid 0 -0.4064)
							(end -0.1397 -0.2667)
						)
						(xy -0.1397 0.4064)
					)
					(width 0)
					(fill yes)
				)
			)
		)
		(pad "15" smd custom
			(at -1.25001 -1.1938 180)
			(size 0.06985 0.06985)
			(layers "F.Cu" "F.Mask" "F.Paste")
			(net "13N4315")
			(options
				(clearance outline)
				(anchor circle)
			)
			(primitives
				(gr_poly
					(pts
						(xy 0.1397 0.4064)
						(arc
							(start 0.1397 -0.2667)
							(mid 0 -0.4064)
							(end -0.1397 -0.2667)
						)
						(xy -0.1397 0.4064)
					)
					(width 0)
					(fill yes)
				)
			)
		)
		(pad "16" smd custom
			(at -1.7018 -0.250012 270)
			(size 0.06985 0.06985)
			(layers "F.Cu" "F.Mask" "F.Paste")
			(net "EXT_3.3V")
			(options
				(clearance outline)
				(anchor circle)
			)
			(primitives
				(gr_poly
					(pts
						(xy 0.1397 0.4064)
						(arc
							(start 0.1397 -0.2667)
							(mid 0 -0.4064)
							(end -0.1397 -0.2667)
						)
						(xy -0.1397 0.4064)
					)
					(width 0)
					(fill yes)
				)
			)
		)
		(pad "17" smd rect
			(at 0 0)
			(size 1.9812 0.9652)
			(layers "F.Cu" "F.Mask" "F.Paste")
			(net "GND")
		)
		(zone
			(layer "F.Cu")
			(hatch none 0.5)
			(connect_pads
				(clearance 0)
			)
			(min_thickness 0.25)
			(keepout
				(tracks allowed)
				(vias not_allowed)
				(pads allowed)
				(copperpour not_allowed)
				(footprints allowed)
			)
			(placement
				(enabled no)
				(sheetname "")
			)
			(fill
				(thermal_gap 0.5)
				(thermal_bridge_width 0.5)
				(island_removal_mode 0)
			)
			(polygon
				(pts
					(arc
						(start 20.6502 6.096)
						(mid 19.9898 6.096)
						(end 20.6502 6.096)
					)
				)
			)
		)
	)
	(footprint ""
		(layer "F.Cu")
		(at 65.659 47.117 180)
		(property "Reference" "R112"
			(at 0 0 180)
			(layer "F.SilkS")
			(hide yes)
			(effects
				(font
					(size 1.27 1.27)
				)
			)
		)
		(property "Value" "3.32K"
			(at -0.148158 1.3462 270)
			(unlocked yes)
			(layer "F.Fab")
			(hide yes)
			(effects
				(font
					(size 1.27 0.9652)
					(thickness 0.000001)
				)
				(justify left)
			)
		)
		(property "Device Type" "REST0061"
			(at -0.148158 1.3462 270)
			(unlocked yes)
			(layer "F.Fab")
			(hide yes)
			(effects
				(font
					(size 1.27 0.9652)
					(thickness 0.000001)
				)
				(justify left)
			)
		)
		(duplicate_pad_numbers_are_jumpers no)
		(fp_poly
			(pts
				(xy 0.635 1.0668) (xy 0.635 -1.0668) (xy -0.635 -1.0668) (xy -0.635 1.0668)
			)
			(stroke
				(width 0)
				(type default)
			)
			(fill no)
			(layer "F.CrtYd")
		)
		(fp_line
			(start 0.254 0.508)
			(end -0.254 0.508)
			(stroke
				(width 0.0254)
				(type default)
			)
			(layer "F.Fab")
		)
		(fp_line
			(start 0.254 -0.508)
			(end 0.254 0.508)
			(stroke
				(width 0.0254)
				(type default)
			)
			(layer "F.Fab")
		)
		(fp_line
			(start -0.254 0.508)
			(end -0.254 -0.508)
			(stroke
				(width 0.0254)
				(type default)
			)
			(layer "F.Fab")
		)
		(fp_line
			(start -0.254 -0.508)
			(end 0.254 -0.508)
			(stroke
				(width 0.0254)
				(type default)
			)
			(layer "F.Fab")
		)
		(pad "1" smd rect
			(at 0 -0.4191 180)
			(size 0.508 0.5334)
			(layers "F.Cu" "F.Mask" "F.Paste")
			(net "11N1953")
		)
		(pad "2" smd rect
			(at 0 0.4191 180)
			(size 0.508 0.5334)
			(layers "F.Cu" "F.Mask" "F.Paste")
			(net "VDD_5.0V")
		)
		(zone
			(layer "F.Cu")
			(hatch none 0.5)
			(connect_pads
				(clearance 0)
			)
			(min_thickness 0.25)
			(keepout
				(tracks not_allowed)
				(vias allowed)
				(pads allowed)
				(copperpour not_allowed)
				(footprints allowed)
			)
			(placement
				(enabled no)
				(sheetname "")
			)
			(fill
				(thermal_gap 0.5)
				(thermal_bridge_width 0.5)
				(island_removal_mode 0)
			)
			(polygon
				(pts
					(xy 65.6336 47.1424) (xy 65.6336 47.0916) (xy 65.6844 47.0916) (xy 65.6844 47.1424)
				)
			)
		)
	)
	(footprint ""
		(layer "F.Cu")
		(at 82.65099 30.612994)
		(property "Reference" "V3_A-A04"
			(at 0 0 0)
			(layer "F.SilkS")
			(hide yes)
			(effects
				(font
					(size 1.27 1.27)
				)
			)
		)
		(property "Value" ""
			(at 0 0 0)
			(layer "F.Fab")
			(effects
				(font
					(size 1.27 1.27)
				)
			)
		)
		(duplicate_pad_numbers_are_jumpers no)
		(pad "1" thru_hole circle
			(at 0 0)
			(size 0.762 0.762)
			(drill 0.20574)
			(layers "*.Cu" "*.Mask")
			(remove_unused_layers no)
			(net "DDR0_32A_A4")
			(clearance 0.127)
			(thermal_gap 0.127)
			(padstack
				(mode front_inner_back)
				(layer "Inner"
					(shape circle)
					(size 0.4572 0.4572)
					(clearance 0.1143)
				)
				(layer "B.Cu"
					(shape circle)
					(size 0.4572 0.4572)
					(clearance 0.1143)
				)
			)
		)
	)
	(footprint ""
		(layer "F.Cu")
		(at 5.08 34.163 180)
		(property "Reference" "R104"
			(at 0 0 180)
			(layer "F.SilkS")
			(hide yes)
			(effects
				(font
					(size 1.27 1.27)
				)
			)
		)
		(property "Value" "4.75K"
			(at -0.148158 1.3462 270)
			(unlocked yes)
			(layer "F.Fab")
			(hide yes)
			(effects
				(font
					(size 1.27 0.9652)
					(thickness 0.000001)
				)
				(justify left)
			)
		)
		(property "Device Type" "REST4024"
			(at -0.148158 1.3462 270)
			(unlocked yes)
			(layer "F.Fab")
			(hide yes)
			(effects
				(font
					(size 1.27 0.9652)
					(thickness 0.000001)
				)
				(justify left)
			)
		)
		(duplicate_pad_numbers_are_jumpers no)
		(fp_poly
			(pts
				(xy 0.635 1.0668) (xy 0.635 -1.0668) (xy -0.635 -1.0668) (xy -0.635 1.0668)
			)
			(stroke
				(width 0)
				(type default)
			)
			(fill no)
			(layer "F.CrtYd")
		)
		(fp_line
			(start 0.254 0.508)
			(end -0.254 0.508)
			(stroke
				(width 0.0254)
				(type default)
			)
			(layer "F.Fab")
		)
		(fp_line
			(start 0.254 -0.508)
			(end 0.254 0.508)
			(stroke
				(width 0.0254)
				(type default)
			)
			(layer "F.Fab")
		)
		(fp_line
			(start -0.254 0.508)
			(end -0.254 -0.508)
			(stroke
				(width 0.0254)
				(type default)
			)
			(layer "F.Fab")
		)
		(fp_line
			(start -0.254 -0.508)
			(end 0.254 -0.508)
			(stroke
				(width 0.0254)
				(type default)
			)
			(layer "F.Fab")
		)
		(pad "1" smd rect
			(at 0 -0.4191 180)
			(size 0.508 0.5334)
			(layers "F.Cu" "F.Mask" "F.Paste")
			(net "11N1966")
		)
		(pad "2" smd rect
			(at 0 0.4191 180)
			(size 0.508 0.5334)
			(layers "F.Cu" "F.Mask" "F.Paste")
			(net "VDD_5.0V")
		)
		(zone
			(layer "F.Cu")
			(hatch none 0.5)
			(connect_pads
				(clearance 0)
			)
			(min_thickness 0.25)
			(keepout
				(tracks not_allowed)
				(vias allowed)
				(pads allowed)
				(copperpour not_allowed)
				(footprints allowed)
			)
			(placement
				(enabled no)
				(sheetname "")
			)
			(fill
				(thermal_gap 0.5)
				(thermal_bridge_width 0.5)
				(island_removal_mode 0)
			)
			(polygon
				(pts
					(xy 5.0546 34.1884) (xy 5.0546 34.1376) (xy 5.1054 34.1376) (xy 5.1054 34.1884)
				)
			)
		)
	)
)
